# BASEBOARD_FAB2 (Tioga Pass) — schematic netlist excerpt (pin names and nets, part order shuffled) for the footprints in the layout excerpt that follows; sources: Cadence DE-HDL packaged netlist, KiCad conversion of Wiwynn_Tioga_Pass_MB.brd

C7G11  CAP  0.22UF 16V 10% X7R  pkg 0402  page 105 : A = P3E_CPU0_PE2_SS_TXP<12> ; B = P3E_CPU0_PE2_SS_C_TXP<12>

(kicad_pcb
	(version 20260206)
	(generator "pcbnew")
	(generator_version "10.0")
	(general
		(thickness 1.6)
		(legacy_teardrops no)
	)
	(paper "A4")
	(title_block
		(title "Wiwynn_Tioga_Pass_MB.brd")
		(comment 1 "Tioga Pass / footprints 36-36 of 4770")
	)
	(layers
		(0 "F.Cu" signal "TOP")
		(4 "In1.Cu" signal "L2GND")
		(6 "In2.Cu" signal "L3")
		(8 "In3.Cu" signal "L4GND")
		(10 "In4.Cu" signal "L5")
		(12 "In5.Cu" signal "L6GND")
		(14 "In6.Cu" signal "L7VCC")
		(16 "In7.Cu" signal "L8VCC")
		(18 "In8.Cu" signal "L9GND")
		(20 "In9.Cu" signal "L10")
		(22 "In10.Cu" signal "L11GND")
		(24 "In11.Cu" signal "L12")
		(26 "In12.Cu" signal "L13GND")
		(2 "B.Cu" signal "BOTTOM")
		(9 "F.Adhes" user "F.Adhesive")
		(11 "B.Adhes" user "B.Adhesive")
		(13 "F.Paste" user "Package Geometry/Pastemask Top")
		(15 "B.Paste" user "Package Geometry/Pastemask Bottom")
		(5 "F.SilkS" user "Ref Des/Silkscreen Top")
		(7 "B.SilkS" user "Ref Des/Silkscreen Bottom")
		(1 "F.Mask" user "Board Geometry/Soldermask Top")
		(3 "B.Mask" user "Board Geometry/Soldermask Bottom")
		(17 "Dwgs.User" user "User.Drawings")
		(19 "Cmts.User" user "User.Comments")
		(21 "Eco1.User" user "User.Eco1")
		(23 "Eco2.User" user "User.Eco2")
		(25 "Edge.Cuts" user "Board Geometry/Outline")
		(27 "Margin" user)
		(31 "F.CrtYd" user "Package Geometry/Place Bound Top")
		(29 "B.CrtYd" user "Package Geometry/Place Bound Bottom")
		(35 "F.Fab" user "Ref Des/Assembly Top")
		(33 "B.Fab" user "Ref Des/Assembly Bottom")
	)
	(footprint ""
		(layer "F.Cu")
		(at 369.477544 -10.916158)
		(property "Reference" "C7G11"
			(at 0 0 0)
			(layer "F.SilkS")
			(hide yes)
			(effects
				(font
					(size 1.27 1.27)
				)
			)
		)
		(property "Value" ""
			(at 0 0 0)
			(layer "F.Fab")
			(effects
				(font
					(size 1.27 1.27)
				)
			)
		)
		(duplicate_pad_numbers_are_jumpers no)
		(fp_rect
			(start -0.3048 0.9906)
			(end 0.3048 -0.1016)
			(stroke
				(width 0)
				(type default)
			)
			(fill no)
			(layer "F.CrtYd")
		)
		(fp_line
			(start -0.3048 -0.1016)
			(end -0.3048 0.9906)
			(stroke
				(width 0.1)
				(type default)
			)
			(layer "F.Fab")
		)
		(fp_line
			(start -0.3048 0.9906)
			(end 0.3048 0.9906)
			(stroke
				(width 0.1)
				(type default)
			)
			(layer "F.Fab")
		)
		(fp_line
			(start 0.3048 -0.1016)
			(end -0.3048 -0.1016)
			(stroke
				(width 0.1)
				(type default)
			)
			(layer "F.Fab")
		)
		(fp_line
			(start 0.3048 0.9906)
			(end 0.3048 -0.1016)
			(stroke
				(width 0.1)
				(type default)
			)
			(layer "F.Fab")
		)
		(pad "1" smd rect
			(at 0 0)
			(size 0.508 0.508)
			(layers "F.Cu" "F.Mask" "F.Paste")
			(net "P3E_CPU0_PE2_SS_TXP<12>")
		)
		(pad "2" smd rect
			(at 0 0.889)
			(size 0.508 0.508)
			(layers "F.Cu" "F.Mask" "F.Paste")
			(net "P3E_CPU0_PE2_SS_C_TXP<12>")
		)
		(zone
			(layer "F.Cu")
			(hatch none 0.5)
			(connect_pads
				(clearance 0)
			)
			(min_thickness 0.25)
			(keepout
				(tracks allowed)
				(vias not_allowed)
				(pads allowed)
				(copperpour not_allowed)
				(footprints allowed)
			)
			(placement
				(enabled no)
				(sheetname "")
			)
			(fill
				(thermal_gap 0.5)
				(thermal_bridge_width 0.5)
				(island_removal_mode 0)
			)
			(polygon
				(pts
					(xy 369.223544 -10.281158) (xy 369.731544 -10.281158) (xy 369.731544 -10.662158) (xy 369.223544 -10.662158)
				)
			)
		)
		(zone
			(layer "F.Cu")
			(hatch none 0.5)
			(connect_pads
				(clearance 0)
			)
			(min_thickness 0.25)
			(keepout
				(tracks not_allowed)
				(vias allowed)
				(pads allowed)
				(copperpour not_allowed)
				(footprints allowed)
			)
			(placement
				(enabled no)
				(sheetname "")
			)
			(fill
				(thermal_gap 0.5)
				(thermal_bridge_width 0.5)
				(island_removal_mode 0)
			)
			(polygon
				(pts
					(xy 369.223544 -10.281158) (xy 369.731544 -10.281158) (xy 369.731544 -10.662158) (xy 369.223544 -10.662158)
				)
			)
		)
	)
)
